FILE_TYPE = MULTI_PHYS_TABLE;

PART 'MOSFET_N_GSD'

{========================================================================================}
:VALUE           | PART_TYPE | MATERIAL | PART_NUMBER      = PART_NUMBER   | JEDEC_TYPE    | DESCRIPTION                               | MANUFTR | MANUF_PN        | RD_CMPLS_LVL | CMPLS_LVL | CLASS | DIP_SMD | FP_ECN | FROM_PJ      | DATA                    | EE_CHECK_LIST | STANDARD        | PSL | PREFERENCE | LIFECYCLE     | CREATOR | CREATEDAY  | STATUS ;
{========================================================================================}
 'IPB027N10N3 G' | 'SMLF'    | 'IC'     | 'BAM027N0000'(!) = 'BAM027N0000' | 'TO263_GDSXA' | 'TRANS MOS IPB027N10N3 G(100V,120A,300W)' | 'SNI'   | 'IPB027N10N3 G' | 'EP(V1)'     | ''        | 'IC'  | ''      | ''     | 'T2L-CHEESE' | 'SNI_IPB027N10N3-G.pdf' | ''            | 'Non-Preferred' | ''  | ''         | 'Preliminary' | ''      | '20120203' | ''    
 'IPB027N10N3 G' | 'SMLF'    | 'EMPTY'  | 'BAM027N0000'(!) = 'BAM027N0000' | 'TO263_GDSXA' | 'TRANS MOS IPB027N10N3 G(100V,120A,300W)' | 'SNI'   | 'IPB027N10N3 G' | 'EP(V1)'     | ''        | 'IC'  | ''      | ''     | 'T2L-CHEESE' | 'SNI_IPB027N10N3-G.pdf' | ''            | 'Non-Preferred' | ''  | ''         | 'Preliminary' | ''      | '20120203' | ''    
 'DMG6968U-7'    | 'SMLF'    | 'IC'     | 'BAM69680000'(!) = 'BAM69680000 ' | 'SOT23_GDSXC' | 'TRANS MOS DMG6968U-7(20V,6.5A,1.3W)SOT23' | 'DDS'   | 'DMG6968U-7'    | 'EP(V1)'     | ''        | 'IC'  | ''      | ''     | 'S1N-AI-JU'  | 'DDS_DMG6968U.pdf'      | ''            | ''              | ''  | ''         | 'P/N RELEASE' | ''      | '20120801' | ''    
 'DMG6968U-7'    | 'SMLF'    | 'EMPTY'  | 'BAM69680000'(!) = 'BAM69680000 ' | 'SOT23_GDSXC' | 'TRANS MOS DMG6968U-7(20V,6.5A,1.3W)SOT23' | 'DDS'   | 'DMG6968U-7'    | 'EP(V1)'     | ''        | 'IC'  | ''      | ''     | 'S1N-AI-JU'  | 'DDS_DMG6968U.pdf'      | ''            | ''              | ''  | ''         | 'P/N RELEASE' | ''      | '20120801' | ''    
 'NX7002AK'      | 'SMLF'    | 'IC'     | 'BAM70020062'(!) = 'BAM70020062 ' | 'SOT23_GDSXE' | 'TRANS MOS NX7002AK(60V,0.19A,0.325W)SMD'  | 'NXP'   | 'NX7002AK'      | 'EP(V1)'     | ''        | 'IC'  | ''      | ''     | 'S1N-AI-JU'  | 'NXP_NX7002AK.pdf'      | ''            | 'Non-Preferred' | ''  | ''         | 'P/N RELEASE' | ''      | '20120801' | ''    
 'NX7002AK'      | 'SMLF'    | 'EMPTY'  | 'BAM70020062'(!) = 'BAM70020062 ' | 'SOT23_GDSXE' | 'TRANS MOS NX7002AK(60V,0.19A,0.325W)SMD'  | 'NXP'   | 'NX7002AK'      | 'EP(V1)'     | ''        | 'IC'  | ''      | ''     | 'S1N-AI-JU'  | 'NXP_NX7002AK.pdf'      | ''            | 'Non-Preferred' | ''  | ''         | 'P/N RELEASE' | ''      | '20120801' | ''    

END_PART

END.

